(kicad_pcb
	(version 20260206)
	(generator "pcbnew")
	(generator_version "10.0")
	(general
		(thickness 1.6)
		(legacy_teardrops no)
	)
	(paper "A4")
	(title_block
		(title "01162023_DA0F0TEBIF0_F0T_Expander_BD_F_brd_V02_OCP.brd")
		(comment 1 "Grand Teton / footprints 1252-1257 of 9728")
	)
	(layers
		(0 "F.Cu" signal "TOP")
		(4 "In1.Cu" signal "GND")
		(6 "In2.Cu" signal "VCC")
		(8 "In3.Cu" signal "VCC1")
		(10 "In4.Cu" signal "GND1")
		(12 "In5.Cu" signal "IN1")
		(14 "In6.Cu" signal "GND2")
		(16 "In7.Cu" signal "IN2")
		(18 "In8.Cu" signal "GND3")
		(20 "In9.Cu" signal "IN3")
		(22 "In10.Cu" signal "GND4")
		(24 "In11.Cu" signal "IN4")
		(26 "In12.Cu" signal "GND5")
		(28 "In13.Cu" signal "IN5")
		(30 "In14.Cu" signal "GND6")
		(32 "In15.Cu" signal "IN6")
		(34 "In16.Cu" signal "GND7")
		(2 "B.Cu" signal "BOTTOM")
		(9 "F.Adhes" user "F.Adhesive")
		(11 "B.Adhes" user "B.Adhesive")
		(13 "F.Paste" user "Package Geometry/Pastemask Top")
		(15 "B.Paste" user "Package Geometry/Pastemask Bottom")
		(5 "F.SilkS" user "Ref Des/Silkscreen Top")
		(7 "B.SilkS" user "Ref Des/Silkscreen Bottom")
		(1 "F.Mask" user "Board Geometry/Soldermask Top")
		(3 "B.Mask" user "Board Geometry/Soldermask Bottom")
		(17 "Dwgs.User" user "User.Drawings")
		(19 "Cmts.User" user "User.Comments")
		(21 "Eco1.User" user "User.Eco1")
		(23 "Eco2.User" user "User.Eco2")
		(25 "Edge.Cuts" user "Board Geometry/Outline")
		(27 "Margin" user)
		(31 "F.CrtYd" user "Package Geometry/Place Bound Top")
		(29 "B.CrtYd" user "Package Geometry/Place Bound Bottom")
		(35 "F.Fab" user "Ref Des/Assembly Top")
		(33 "B.Fab" user "Ref Des/Assembly Bottom")
	)
	(footprint ""
		(layer "F.Cu")
		(at 304.87493 -56.977534 180)
		(property "Reference" "PC364"
			(at 0 0 180)
			(layer "F.SilkS")
			(hide yes)
			(effects
				(font
					(size 1.27 1.27)
				)
			)
		)
		(property "Value" ""
			(at 0 0 180)
			(layer "F.Fab")
			(effects
				(font
					(size 1.27 1.27)
				)
			)
		)
		(duplicate_pad_numbers_are_jumpers no)
		(fp_line
			(start 0.7874 0.4064)
			(end -0.7874 0.4064)
			(stroke
				(width 0.1524)
				(type default)
			)
			(layer "F.SilkS")
		)
		(fp_line
			(start 0.7874 -0.4064)
			(end 0.7874 0.4064)
			(stroke
				(width 0.1524)
				(type default)
			)
			(layer "F.SilkS")
		)
		(fp_line
			(start -0.7874 0.4064)
			(end -0.7874 -0.4064)
			(stroke
				(width 0.1524)
				(type default)
			)
			(layer "F.SilkS")
		)
		(fp_line
			(start -0.7874 -0.4064)
			(end 0.7874 -0.4064)
			(stroke
				(width 0.1524)
				(type default)
			)
			(layer "F.SilkS")
		)
		(fp_line
			(start 0.67945 0.3048)
			(end 0.120396 0.3048)
			(stroke
				(width 0.1)
				(type default)
			)
			(layer "F.Fab")
		)
		(fp_line
			(start 0.67945 -0.3048)
			(end 0.67945 0.3048)
			(stroke
				(width 0.1)
				(type default)
			)
			(layer "F.Fab")
		)
		(fp_line
			(start 0.12065 -0.2794)
			(end 0.12065 -0.3048)
			(stroke
				(width 0.1)
				(type default)
			)
			(layer "F.Fab")
		)
		(fp_line
			(start 0.12065 -0.3048)
			(end 0.67945 -0.3048)
			(stroke
				(width 0.1)
				(type default)
			)
			(layer "F.Fab")
		)
		(fp_line
			(start 0.120396 0.3048)
			(end 0.120396 0.2794)
			(stroke
				(width 0.1)
				(type default)
			)
			(layer "F.Fab")
		)
		(fp_line
			(start 0.120396 0.2794)
			(end -0.12065 0.2794)
			(stroke
				(width 0.1)
				(type default)
			)
			(layer "F.Fab")
		)
		(fp_line
			(start -0.12065 0.3048)
			(end -0.67945 0.3048)
			(stroke
				(width 0.1)
				(type default)
			)
			(layer "F.Fab")
		)
		(fp_line
			(start -0.12065 0.2794)
			(end -0.12065 0.3048)
			(stroke
				(width 0.1)
				(type default)
			)
			(layer "F.Fab")
		)
		(fp_line
			(start -0.12065 -0.2794)
			(end 0.12065 -0.2794)
			(stroke
				(width 0.1)
				(type default)
			)
			(layer "F.Fab")
		)
		(fp_line
			(start -0.12065 -0.305054)
			(end -0.12065 -0.2794)
			(stroke
				(width 0.1)
				(type default)
			)
			(layer "F.Fab")
		)
		(fp_line
			(start -0.67945 0.3048)
			(end -0.67945 -0.305054)
			(stroke
				(width 0.1)
				(type default)
			)
			(layer "F.Fab")
		)
		(fp_line
			(start -0.67945 -0.305054)
			(end -0.12065 -0.305054)
			(stroke
				(width 0.1)
				(type default)
			)
			(layer "F.Fab")
		)
		(pad "1" smd circle
			(at -0.40005 0 180)
			(size 0 0)
			(layers "F.Cu" "F.Mask" "F.Paste")
			(net "P12V_AUX")
		)
		(pad "2" smd circle
			(at 0.40005 0 180)
			(size 0 0)
			(layers "F.Cu" "F.Mask" "F.Paste")
			(net "GND")
		)
	)
	(footprint ""
		(layer "F.Cu")
		(at 344.675968 -279.101804)
		(property "Reference" "PC156"
			(at 0 0 0)
			(layer "F.SilkS")
			(hide yes)
			(effects
				(font
					(size 1.27 1.27)
				)
			)
		)
		(property "Value" ""
			(at 0 0 0)
			(layer "F.Fab")
			(effects
				(font
					(size 1.27 1.27)
				)
			)
		)
		(duplicate_pad_numbers_are_jumpers no)
		(fp_line
			(start -0.7874 -0.4064)
			(end 0.7874 -0.4064)
			(stroke
				(width 0.1524)
				(type default)
			)
			(layer "F.SilkS")
		)
		(fp_line
			(start -0.7874 0.4064)
			(end -0.7874 -0.4064)
			(stroke
				(width 0.1524)
				(type default)
			)
			(layer "F.SilkS")
		)
		(fp_line
			(start 0.7874 -0.4064)
			(end 0.7874 0.4064)
			(stroke
				(width 0.1524)
				(type default)
			)
			(layer "F.SilkS")
		)
		(fp_line
			(start 0.7874 0.4064)
			(end -0.7874 0.4064)
			(stroke
				(width 0.1524)
				(type default)
			)
			(layer "F.SilkS")
		)
		(fp_line
			(start -0.67945 -0.305054)
			(end -0.12065 -0.305054)
			(stroke
				(width 0.1)
				(type default)
			)
			(layer "F.Fab")
		)
		(fp_line
			(start -0.67945 0.3048)
			(end -0.67945 -0.305054)
			(stroke
				(width 0.1)
				(type default)
			)
			(layer "F.Fab")
		)
		(fp_line
			(start -0.12065 -0.305054)
			(end -0.12065 -0.2794)
			(stroke
				(width 0.1)
				(type default)
			)
			(layer "F.Fab")
		)
		(fp_line
			(start -0.12065 -0.2794)
			(end 0.12065 -0.2794)
			(stroke
				(width 0.1)
				(type default)
			)
			(layer "F.Fab")
		)
		(fp_line
			(start -0.12065 0.2794)
			(end -0.12065 0.3048)
			(stroke
				(width 0.1)
				(type default)
			)
			(layer "F.Fab")
		)
		(fp_line
			(start -0.12065 0.3048)
			(end -0.67945 0.3048)
			(stroke
				(width 0.1)
				(type default)
			)
			(layer "F.Fab")
		)
		(fp_line
			(start 0.120396 0.2794)
			(end -0.12065 0.2794)
			(stroke
				(width 0.1)
				(type default)
			)
			(layer "F.Fab")
		)
		(fp_line
			(start 0.120396 0.3048)
			(end 0.120396 0.2794)
			(stroke
				(width 0.1)
				(type default)
			)
			(layer "F.Fab")
		)
		(fp_line
			(start 0.12065 -0.3048)
			(end 0.67945 -0.3048)
			(stroke
				(width 0.1)
				(type default)
			)
			(layer "F.Fab")
		)
		(fp_line
			(start 0.12065 -0.2794)
			(end 0.12065 -0.3048)
			(stroke
				(width 0.1)
				(type default)
			)
			(layer "F.Fab")
		)
		(fp_line
			(start 0.67945 -0.3048)
			(end 0.67945 0.3048)
			(stroke
				(width 0.1)
				(type default)
			)
			(layer "F.Fab")
		)
		(fp_line
			(start 0.67945 0.3048)
			(end 0.120396 0.3048)
			(stroke
				(width 0.1)
				(type default)
			)
			(layer "F.Fab")
		)
		(pad "1" smd circle
			(at -0.40005 0)
			(size 0 0)
			(layers "F.Cu" "F.Mask" "F.Paste")
			(net "SW_P12V_P0V8_PEX2_FLT")
		)
		(pad "2" smd circle
			(at 0.40005 0)
			(size 0 0)
			(layers "F.Cu" "F.Mask" "F.Paste")
			(net "GND")
		)
	)
	(footprint ""
		(layer "F.Cu")
		(at 365.506 -207.899 180)
		(property "Reference" "R4627"
			(at 0 0 180)
			(layer "F.SilkS")
			(hide yes)
			(effects
				(font
					(size 1.27 1.27)
				)
			)
		)
		(property "Value" ""
			(at 0 0 180)
			(layer "F.Fab")
			(effects
				(font
					(size 1.27 1.27)
				)
			)
		)
		(duplicate_pad_numbers_are_jumpers no)
		(fp_line
			(start 0.7874 0.4064)
			(end -0.7874 0.4064)
			(stroke
				(width 0.1524)
				(type default)
			)
			(layer "F.SilkS")
		)
		(fp_line
			(start 0.7874 -0.4064)
			(end 0.7874 0.4064)
			(stroke
				(width 0.1524)
				(type default)
			)
			(layer "F.SilkS")
		)
		(fp_line
			(start -0.7874 0.4064)
			(end -0.7874 -0.4064)
			(stroke
				(width 0.1524)
				(type default)
			)
			(layer "F.SilkS")
		)
		(fp_line
			(start -0.7874 -0.4064)
			(end 0.7874 -0.4064)
			(stroke
				(width 0.1524)
				(type default)
			)
			(layer "F.SilkS")
		)
		(fp_line
			(start 0.67945 0.3048)
			(end 0.120396 0.3048)
			(stroke
				(width 0.1)
				(type default)
			)
			(layer "F.Fab")
		)
		(fp_line
			(start 0.67945 -0.3048)
			(end 0.67945 0.3048)
			(stroke
				(width 0.1)
				(type default)
			)
			(layer "F.Fab")
		)
		(fp_line
			(start 0.12065 -0.2794)
			(end 0.12065 -0.3048)
			(stroke
				(width 0.1)
				(type default)
			)
			(layer "F.Fab")
		)
		(fp_line
			(start 0.12065 -0.3048)
			(end 0.67945 -0.3048)
			(stroke
				(width 0.1)
				(type default)
			)
			(layer "F.Fab")
		)
		(fp_line
			(start 0.120396 0.3048)
			(end 0.120396 0.2794)
			(stroke
				(width 0.1)
				(type default)
			)
			(layer "F.Fab")
		)
		(fp_line
			(start 0.120396 0.2794)
			(end -0.12065 0.2794)
			(stroke
				(width 0.1)
				(type default)
			)
			(layer "F.Fab")
		)
		(fp_line
			(start -0.12065 0.3048)
			(end -0.67945 0.3048)
			(stroke
				(width 0.1)
				(type default)
			)
			(layer "F.Fab")
		)
		(fp_line
			(start -0.12065 0.2794)
			(end -0.12065 0.3048)
			(stroke
				(width 0.1)
				(type default)
			)
			(layer "F.Fab")
		)
		(fp_line
			(start -0.12065 -0.2794)
			(end 0.12065 -0.2794)
			(stroke
				(width 0.1)
				(type default)
			)
			(layer "F.Fab")
		)
		(fp_line
			(start -0.12065 -0.305054)
			(end -0.12065 -0.2794)
			(stroke
				(width 0.1)
				(type default)
			)
			(layer "F.Fab")
		)
		(fp_line
			(start -0.67945 0.3048)
			(end -0.67945 -0.305054)
			(stroke
				(width 0.1)
				(type default)
			)
			(layer "F.Fab")
		)
		(fp_line
			(start -0.67945 -0.305054)
			(end -0.12065 -0.305054)
			(stroke
				(width 0.1)
				(type default)
			)
			(layer "F.Fab")
		)
		(pad "1" smd circle
			(at -0.40005 0 180)
			(size 0 0)
			(layers "F.Cu" "F.Mask" "F.Paste")
			(net "PRSNT_SSD1_FPGA_PCA9555_N")
		)
		(pad "2" smd circle
			(at 0.40005 0 180)
			(size 0 0)
			(layers "F.Cu" "F.Mask" "F.Paste")
			(net "PRSNT_SSD1_FPGA_R_N")
		)
	)
	(footprint ""
		(layer "F.Cu")
		(at 248.094754 -273.471386)
		(property "Reference" "R793"
			(at 0 0 0)
			(layer "F.SilkS")
			(hide yes)
			(effects
				(font
					(size 1.27 1.27)
				)
			)
		)
		(property "Value" ""
			(at 0 0 0)
			(layer "F.Fab")
			(effects
				(font
					(size 1.27 1.27)
				)
			)
		)
		(duplicate_pad_numbers_are_jumpers no)
		(fp_line
			(start -0.7874 -0.4064)
			(end 0.7874 -0.4064)
			(stroke
				(width 0.1524)
				(type default)
			)
			(layer "F.SilkS")
		)
		(fp_line
			(start -0.7874 0.4064)
			(end -0.7874 -0.4064)
			(stroke
				(width 0.1524)
				(type default)
			)
			(layer "F.SilkS")
		)
		(fp_line
			(start 0.7874 -0.4064)
			(end 0.7874 0.4064)
			(stroke
				(width 0.1524)
				(type default)
			)
			(layer "F.SilkS")
		)
		(fp_line
			(start 0.7874 0.4064)
			(end -0.7874 0.4064)
			(stroke
				(width 0.1524)
				(type default)
			)
			(layer "F.SilkS")
		)
		(fp_line
			(start -0.67945 -0.305054)
			(end -0.12065 -0.305054)
			(stroke
				(width 0.1)
				(type default)
			)
			(layer "F.Fab")
		)
		(fp_line
			(start -0.67945 0.3048)
			(end -0.67945 -0.305054)
			(stroke
				(width 0.1)
				(type default)
			)
			(layer "F.Fab")
		)
		(fp_line
			(start -0.12065 -0.305054)
			(end -0.12065 -0.2794)
			(stroke
				(width 0.1)
				(type default)
			)
			(layer "F.Fab")
		)
		(fp_line
			(start -0.12065 -0.2794)
			(end 0.12065 -0.2794)
			(stroke
				(width 0.1)
				(type default)
			)
			(layer "F.Fab")
		)
		(fp_line
			(start -0.12065 0.2794)
			(end -0.12065 0.3048)
			(stroke
				(width 0.1)
				(type default)
			)
			(layer "F.Fab")
		)
		(fp_line
			(start -0.12065 0.3048)
			(end -0.67945 0.3048)
			(stroke
				(width 0.1)
				(type default)
			)
			(layer "F.Fab")
		)
		(fp_line
			(start 0.120396 0.2794)
			(end -0.12065 0.2794)
			(stroke
				(width 0.1)
				(type default)
			)
			(layer "F.Fab")
		)
		(fp_line
			(start 0.120396 0.3048)
			(end 0.120396 0.2794)
			(stroke
				(width 0.1)
				(type default)
			)
			(layer "F.Fab")
		)
		(fp_line
			(start 0.12065 -0.3048)
			(end 0.67945 -0.3048)
			(stroke
				(width 0.1)
				(type default)
			)
			(layer "F.Fab")
		)
		(fp_line
			(start 0.12065 -0.2794)
			(end 0.12065 -0.3048)
			(stroke
				(width 0.1)
				(type default)
			)
			(layer "F.Fab")
		)
		(fp_line
			(start 0.67945 -0.3048)
			(end 0.67945 0.3048)
			(stroke
				(width 0.1)
				(type default)
			)
			(layer "F.Fab")
		)
		(fp_line
			(start 0.67945 0.3048)
			(end 0.120396 0.3048)
			(stroke
				(width 0.1)
				(type default)
			)
			(layer "F.Fab")
		)
		(pad "1" smd circle
			(at -0.40005 0)
			(size 0 0)
			(layers "F.Cu" "F.Mask" "F.Paste")
			(net "PEX2_P1V25_ADC_A1")
		)
		(pad "2" smd circle
			(at 0.40005 0)
			(size 0 0)
			(layers "F.Cu" "F.Mask" "F.Paste")
			(net "P3V3_AUX")
		)
	)
	(footprint ""
		(layer "F.Cu")
		(at 369.495578 -87.213694 180)
		(property "Reference" "R1610"
			(at 0 0 180)
			(layer "F.SilkS")
			(hide yes)
			(effects
				(font
					(size 1.27 1.27)
				)
			)
		)
		(property "Value" ""
			(at 0 0 180)
			(layer "F.Fab")
			(effects
				(font
					(size 1.27 1.27)
				)
			)
		)
		(duplicate_pad_numbers_are_jumpers no)
		(fp_line
			(start 0.7874 0.4064)
			(end -0.7874 0.4064)
			(stroke
				(width 0.1524)
				(type default)
			)
			(layer "F.SilkS")
		)
		(fp_line
			(start 0.7874 -0.4064)
			(end 0.7874 0.4064)
			(stroke
				(width 0.1524)
				(type default)
			)
			(layer "F.SilkS")
		)
		(fp_line
			(start -0.7874 0.4064)
			(end -0.7874 -0.4064)
			(stroke
				(width 0.1524)
				(type default)
			)
			(layer "F.SilkS")
		)
		(fp_line
			(start -0.7874 -0.4064)
			(end 0.7874 -0.4064)
			(stroke
				(width 0.1524)
				(type default)
			)
			(layer "F.SilkS")
		)
		(fp_line
			(start 0.67945 0.3048)
			(end 0.120396 0.3048)
			(stroke
				(width 0.1)
				(type default)
			)
			(layer "F.Fab")
		)
		(fp_line
			(start 0.67945 -0.3048)
			(end 0.67945 0.3048)
			(stroke
				(width 0.1)
				(type default)
			)
			(layer "F.Fab")
		)
		(fp_line
			(start 0.12065 -0.2794)
			(end 0.12065 -0.3048)
			(stroke
				(width 0.1)
				(type default)
			)
			(layer "F.Fab")
		)
		(fp_line
			(start 0.12065 -0.3048)
			(end 0.67945 -0.3048)
			(stroke
				(width 0.1)
				(type default)
			)
			(layer "F.Fab")
		)
		(fp_line
			(start 0.120396 0.3048)
			(end 0.120396 0.2794)
			(stroke
				(width 0.1)
				(type default)
			)
			(layer "F.Fab")
		)
		(fp_line
			(start 0.120396 0.2794)
			(end -0.12065 0.2794)
			(stroke
				(width 0.1)
				(type default)
			)
			(layer "F.Fab")
		)
		(fp_line
			(start -0.12065 0.3048)
			(end -0.67945 0.3048)
			(stroke
				(width 0.1)
				(type default)
			)
			(layer "F.Fab")
		)
		(fp_line
			(start -0.12065 0.2794)
			(end -0.12065 0.3048)
			(stroke
				(width 0.1)
				(type default)
			)
			(layer "F.Fab")
		)
		(fp_line
			(start -0.12065 -0.2794)
			(end 0.12065 -0.2794)
			(stroke
				(width 0.1)
				(type default)
			)
			(layer "F.Fab")
		)
		(fp_line
			(start -0.12065 -0.305054)
			(end -0.12065 -0.2794)
			(stroke
				(width 0.1)
				(type default)
			)
			(layer "F.Fab")
		)
		(fp_line
			(start -0.67945 0.3048)
			(end -0.67945 -0.305054)
			(stroke
				(width 0.1)
				(type default)
			)
			(layer "F.Fab")
		)
		(fp_line
			(start -0.67945 -0.305054)
			(end -0.12065 -0.305054)
			(stroke
				(width 0.1)
				(type default)
			)
			(layer "F.Fab")
		)
		(pad "1" smd circle
			(at -0.40005 0 180)
			(size 0 0)
			(layers "F.Cu" "F.Mask" "F.Paste")
			(net "P3V3_AUX")
		)
		(pad "2" smd circle
			(at 0.40005 0 180)
			(size 0 0)
			(layers "F.Cu" "F.Mask" "F.Paste")
			(net "SMB_BIC_I2C9_MUX1_SSD14_R_SCL")
		)
	)
	(footprint ""
		(layer "F.Cu")
		(at 270.807942 -160.380934)
		(property "Reference" "R227"
			(at 0 0 0)
			(layer "F.SilkS")
			(hide yes)
			(effects
				(font
					(size 1.27 1.27)
				)
			)
		)
		(property "Value" ""
			(at 0 0 0)
			(layer "F.Fab")
			(effects
				(font
					(size 1.27 1.27)
				)
			)
		)
		(duplicate_pad_numbers_are_jumpers no)
		(fp_line
			(start -0.7874 -0.4064)
			(end 0.7874 -0.4064)
			(stroke
				(width 0.1524)
				(type default)
			)
			(layer "F.SilkS")
		)
		(fp_line
			(start -0.7874 0.4064)
			(end -0.7874 -0.4064)
			(stroke
				(width 0.1524)
				(type default)
			)
			(layer "F.SilkS")
		)
		(fp_line
			(start 0.7874 -0.4064)
			(end 0.7874 0.4064)
			(stroke
				(width 0.1524)
				(type default)
			)
			(layer "F.SilkS")
		)
		(fp_line
			(start 0.7874 0.4064)
			(end -0.7874 0.4064)
			(stroke
				(width 0.1524)
				(type default)
			)
			(layer "F.SilkS")
		)
		(fp_line
			(start -0.67945 -0.305054)
			(end -0.12065 -0.305054)
			(stroke
				(width 0.1)
				(type default)
			)
			(layer "F.Fab")
		)
		(fp_line
			(start -0.67945 0.3048)
			(end -0.67945 -0.305054)
			(stroke
				(width 0.1)
				(type default)
			)
			(layer "F.Fab")
		)
		(fp_line
			(start -0.12065 -0.305054)
			(end -0.12065 -0.2794)
			(stroke
				(width 0.1)
				(type default)
			)
			(layer "F.Fab")
		)
		(fp_line
			(start -0.12065 -0.2794)
			(end 0.12065 -0.2794)
			(stroke
				(width 0.1)
				(type default)
			)
			(layer "F.Fab")
		)
		(fp_line
			(start -0.12065 0.2794)
			(end -0.12065 0.3048)
			(stroke
				(width 0.1)
				(type default)
			)
			(layer "F.Fab")
		)
		(fp_line
			(start -0.12065 0.3048)
			(end -0.67945 0.3048)
			(stroke
				(width 0.1)
				(type default)
			)
			(layer "F.Fab")
		)
		(fp_line
			(start 0.120396 0.2794)
			(end -0.12065 0.2794)
			(stroke
				(width 0.1)
				(type default)
			)
			(layer "F.Fab")
		)
		(fp_line
			(start 0.120396 0.3048)
			(end 0.120396 0.2794)
			(stroke
				(width 0.1)
				(type default)
			)
			(layer "F.Fab")
		)
		(fp_line
			(start 0.12065 -0.3048)
			(end 0.67945 -0.3048)
			(stroke
				(width 0.1)
				(type default)
			)
			(layer "F.Fab")
		)
		(fp_line
			(start 0.12065 -0.2794)
			(end 0.12065 -0.3048)
			(stroke
				(width 0.1)
				(type default)
			)
			(layer "F.Fab")
		)
		(fp_line
			(start 0.67945 -0.3048)
			(end 0.67945 0.3048)
			(stroke
				(width 0.1)
				(type default)
			)
			(layer "F.Fab")
		)
		(fp_line
			(start 0.67945 0.3048)
			(end 0.120396 0.3048)
			(stroke
				(width 0.1)
				(type default)
			)
			(layer "F.Fab")
		)
		(pad "1" smd circle
			(at -0.40005 0)
			(size 0 0)
			(layers "F.Cu" "F.Mask" "F.Paste")
			(net "NIC4_MAIN_PWR_EN")
		)
		(pad "2" smd circle
			(at 0.40005 0)
			(size 0 0)
			(layers "F.Cu" "F.Mask" "F.Paste")
			(net "GND")
		)
	)
)
